# S9S_MB_2U (Grand Teton) — schematic netlist excerpt (pin names and nets, part order shuffled) for the footprints in the layout excerpt that follows; sources: Cadence DE-HDL packaged netlist, KiCad conversion of 03242023_DA0F0TMBIJ0_F0T_Motherboard_J_brd_V01_OCP.brd

R2918  Q_RES  4.7K 5% CHIP  pkg 0402LF  page 149 : A = FM_SWB_PWR_EN_R ; B = GND
R3473  Q_RES  100K 1% EMPTY  pkg 0402LF  page 147 : A = GPU_PRSNT_N ; B = GND

(kicad_pcb
	(version 20260206)
	(generator "pcbnew")
	(generator_version "10.0")
	(general
		(thickness 1.6)
		(legacy_teardrops no)
	)
	(paper "A4")
	(title_block
		(title "03242023_DA0F0TMBIJ0_F0T_Motherboard_J_brd_V01_OCP.brd")
		(comment 1 "Grand Teton / footprints 2075-2076 of 6105")
	)
	(layers
		(0 "F.Cu" signal "TOP")
		(4 "In1.Cu" signal "GND")
		(6 "In2.Cu" signal "IN1")
		(8 "In3.Cu" signal "GND1")
		(10 "In4.Cu" signal "IN2")
		(12 "In5.Cu" signal "GND2")
		(14 "In6.Cu" signal "IN3")
		(16 "In7.Cu" signal "GND3")
		(18 "In8.Cu" signal "VCC")
		(20 "In9.Cu" signal "VCC1")
		(22 "In10.Cu" signal "GND4")
		(24 "In11.Cu" signal "IN4")
		(26 "In12.Cu" signal "GND5")
		(28 "In13.Cu" signal "IN5")
		(30 "In14.Cu" signal "GND6")
		(32 "In15.Cu" signal "IN6")
		(34 "In16.Cu" signal "GND7")
		(2 "B.Cu" signal "BOTTOM")
		(9 "F.Adhes" user "F.Adhesive")
		(11 "B.Adhes" user "B.Adhesive")
		(13 "F.Paste" user "Package Geometry/Pastemask Top")
		(15 "B.Paste" user "Package Geometry/Pastemask Bottom")
		(5 "F.SilkS" user "Ref Des/Silkscreen Top")
		(7 "B.SilkS" user "Ref Des/Silkscreen Bottom")
		(1 "F.Mask" user "Board Geometry/Soldermask Top")
		(3 "B.Mask" user "Board Geometry/Soldermask Bottom")
		(17 "Dwgs.User" user "User.Drawings")
		(19 "Cmts.User" user "User.Comments")
		(21 "Eco1.User" user "User.Eco1")
		(23 "Eco2.User" user "User.Eco2")
		(25 "Edge.Cuts" user "Board Geometry/Outline")
		(27 "Margin" user)
		(31 "F.CrtYd" user "Package Geometry/Place Bound Top")
		(29 "B.CrtYd" user "Package Geometry/Place Bound Bottom")
		(35 "F.Fab" user "Ref Des/Assembly Top")
		(33 "B.Fab" user "Ref Des/Assembly Bottom")
	)
	(footprint ""
		(layer "F.Cu")
		(at 22.91588 -429.351948 180)
		(property "Reference" "R2918"
			(at 0 0 180)
			(layer "F.SilkS")
			(hide yes)
			(effects
				(font
					(size 1.27 1.27)
				)
			)
		)
		(property "Value" ""
			(at 0 0 180)
			(layer "F.Fab")
			(effects
				(font
					(size 1.27 1.27)
				)
			)
		)
		(duplicate_pad_numbers_are_jumpers no)
		(fp_line
			(start 0.7874 0.4064)
			(end -0.7874 0.4064)
			(stroke
				(width 0.1524)
				(type default)
			)
			(layer "F.SilkS")
		)
		(fp_line
			(start 0.7874 -0.4064)
			(end 0.7874 0.4064)
			(stroke
				(width 0.1524)
				(type default)
			)
			(layer "F.SilkS")
		)
		(fp_line
			(start -0.7874 0.4064)
			(end -0.7874 -0.4064)
			(stroke
				(width 0.1524)
				(type default)
			)
			(layer "F.SilkS")
		)
		(fp_line
			(start -0.7874 -0.4064)
			(end 0.7874 -0.4064)
			(stroke
				(width 0.1524)
				(type default)
			)
			(layer "F.SilkS")
		)
		(fp_line
			(start 0.67945 0.3048)
			(end 0.120396 0.3048)
			(stroke
				(width 0.1)
				(type default)
			)
			(layer "F.Fab")
		)
		(fp_line
			(start 0.67945 -0.3048)
			(end 0.67945 0.3048)
			(stroke
				(width 0.1)
				(type default)
			)
			(layer "F.Fab")
		)
		(fp_line
			(start 0.12065 -0.2794)
			(end 0.12065 -0.3048)
			(stroke
				(width 0.1)
				(type default)
			)
			(layer "F.Fab")
		)
		(fp_line
			(start 0.12065 -0.3048)
			(end 0.67945 -0.3048)
			(stroke
				(width 0.1)
				(type default)
			)
			(layer "F.Fab")
		)
		(fp_line
			(start 0.120396 0.3048)
			(end 0.120396 0.2794)
			(stroke
				(width 0.1)
				(type default)
			)
			(layer "F.Fab")
		)
		(fp_line
			(start 0.120396 0.2794)
			(end -0.12065 0.2794)
			(stroke
				(width 0.1)
				(type default)
			)
			(layer "F.Fab")
		)
		(fp_line
			(start -0.12065 0.3048)
			(end -0.67945 0.3048)
			(stroke
				(width 0.1)
				(type default)
			)
			(layer "F.Fab")
		)
		(fp_line
			(start -0.12065 0.2794)
			(end -0.12065 0.3048)
			(stroke
				(width 0.1)
				(type default)
			)
			(layer "F.Fab")
		)
		(fp_line
			(start -0.12065 -0.2794)
			(end 0.12065 -0.2794)
			(stroke
				(width 0.1)
				(type default)
			)
			(layer "F.Fab")
		)
		(fp_line
			(start -0.12065 -0.305054)
			(end -0.12065 -0.2794)
			(stroke
				(width 0.1)
				(type default)
			)
			(layer "F.Fab")
		)
		(fp_line
			(start -0.67945 0.3048)
			(end -0.67945 -0.305054)
			(stroke
				(width 0.1)
				(type default)
			)
			(layer "F.Fab")
		)
		(fp_line
			(start -0.67945 -0.305054)
			(end -0.12065 -0.305054)
			(stroke
				(width 0.1)
				(type default)
			)
			(layer "F.Fab")
		)
		(pad "1" smd circle
			(at -0.40005 0 180)
			(size 0 0)
			(layers "F.Cu" "F.Mask" "F.Paste")
			(net "FM_SWB_PWR_EN_R")
		)
		(pad "2" smd circle
			(at 0.40005 0 180)
			(size 0 0)
			(layers "F.Cu" "F.Mask" "F.Paste")
			(net "GND")
		)
	)
	(footprint ""
		(layer "F.Cu")
		(at 24.069802 -412.450534 180)
		(property "Reference" "R3473"
			(at 0 0 180)
			(layer "F.SilkS")
			(hide yes)
			(effects
				(font
					(size 1.27 1.27)
				)
			)
		)
		(property "Value" ""
			(at 0 0 180)
			(layer "F.Fab")
			(effects
				(font
					(size 1.27 1.27)
				)
			)
		)
		(duplicate_pad_numbers_are_jumpers no)
		(fp_line
			(start 0.7874 0.4064)
			(end -0.7874 0.4064)
			(stroke
				(width 0.1524)
				(type default)
			)
			(layer "F.SilkS")
		)
		(fp_line
			(start 0.7874 -0.4064)
			(end 0.7874 0.4064)
			(stroke
				(width 0.1524)
				(type default)
			)
			(layer "F.SilkS")
		)
		(fp_line
			(start -0.7874 0.4064)
			(end -0.7874 -0.4064)
			(stroke
				(width 0.1524)
				(type default)
			)
			(layer "F.SilkS")
		)
		(fp_line
			(start -0.7874 -0.4064)
			(end 0.7874 -0.4064)
			(stroke
				(width 0.1524)
				(type default)
			)
			(layer "F.SilkS")
		)
		(fp_line
			(start 0.67945 0.3048)
			(end 0.120396 0.3048)
			(stroke
				(width 0.1)
				(type default)
			)
			(layer "F.Fab")
		)
		(fp_line
			(start 0.67945 -0.3048)
			(end 0.67945 0.3048)
			(stroke
				(width 0.1)
				(type default)
			)
			(layer "F.Fab")
		)
		(fp_line
			(start 0.12065 -0.2794)
			(end 0.12065 -0.3048)
			(stroke
				(width 0.1)
				(type default)
			)
			(layer "F.Fab")
		)
		(fp_line
			(start 0.12065 -0.3048)
			(end 0.67945 -0.3048)
			(stroke
				(width 0.1)
				(type default)
			)
			(layer "F.Fab")
		)
		(fp_line
			(start 0.120396 0.3048)
			(end 0.120396 0.2794)
			(stroke
				(width 0.1)
				(type default)
			)
			(layer "F.Fab")
		)
		(fp_line
			(start 0.120396 0.2794)
			(end -0.12065 0.2794)
			(stroke
				(width 0.1)
				(type default)
			)
			(layer "F.Fab")
		)
		(fp_line
			(start -0.12065 0.3048)
			(end -0.67945 0.3048)
			(stroke
				(width 0.1)
				(type default)
			)
			(layer "F.Fab")
		)
		(fp_line
			(start -0.12065 0.2794)
			(end -0.12065 0.3048)
			(stroke
				(width 0.1)
				(type default)
			)
			(layer "F.Fab")
		)
		(fp_line
			(start -0.12065 -0.2794)
			(end 0.12065 -0.2794)
			(stroke
				(width 0.1)
				(type default)
			)
			(layer "F.Fab")
		)
		(fp_line
			(start -0.12065 -0.305054)
			(end -0.12065 -0.2794)
			(stroke
				(width 0.1)
				(type default)
			)
			(layer "F.Fab")
		)
		(fp_line
			(start -0.67945 0.3048)
			(end -0.67945 -0.305054)
			(stroke
				(width 0.1)
				(type default)
			)
			(layer "F.Fab")
		)
		(fp_line
			(start -0.67945 -0.305054)
			(end -0.12065 -0.305054)
			(stroke
				(width 0.1)
				(type default)
			)
			(layer "F.Fab")
		)
		(pad "1" smd circle
			(at -0.40005 0 180)
			(size 0 0)
			(layers "F.Cu" "F.Mask" "F.Paste")
			(net "GPU_PRSNT_N")
		)
		(pad "2" smd circle
			(at 0.40005 0 180)
			(size 0 0)
			(layers "F.Cu" "F.Mask" "F.Paste")
			(net "GND")
		)
	)
)
